(kicad_pcb
	(version 20241229)
	(generator "pcbnew")
	(generator_version "9.0")
	(general
		(thickness 1.6296)
		(legacy_teardrops no)
	)
	(paper "A3")
	(title_block
		(title "Thunderbolt to 10GbE adapter")
		(date "2026-04-21")
		(rev "1.1.0")
		(company "Antmicro Ltd")
		(comment 1 "www.antmicro.com")
		(comment 9 "footprints 560-563 of 703")
	)
	(layers
		(0 "F.Cu" signal)
		(4 "In1.Cu" signal)
		(6 "In2.Cu" signal)
		(8 "In3.Cu" signal)
		(10 "In4.Cu" signal)
		(12 "In5.Cu" signal)
		(14 "In6.Cu" signal)
		(2 "B.Cu" signal)
		(9 "F.Adhes" user "F.Adhesive")
		(11 "B.Adhes" user "B.Adhesive")
		(13 "F.Paste" user)
		(15 "B.Paste" user)
		(5 "F.SilkS" user "F.Silkscreen")
		(7 "B.SilkS" user "B.Silkscreen")
		(1 "F.Mask" user)
		(3 "B.Mask" user)
		(17 "Dwgs.User" user "User.Drawings")
		(19 "Cmts.User" user "User.Comments")
		(21 "Eco1.User" user "User.Eco1")
		(23 "Eco2.User" user "User.Eco2")
		(25 "Edge.Cuts" user)
		(27 "Margin" user)
		(31 "F.CrtYd" user "F.Courtyard")
		(29 "B.CrtYd" user "B.Courtyard")
		(35 "F.Fab" user)
		(33 "B.Fab" user)
	)
	(footprint "antmicro-footprints:C_0402_1005Metric"
		(layer "B.Cu")
		(at 159.406866 85.485117 90)
		(descr "Capacitor SMD 0402")
		(tags "capacitor SMD 0402")
		(property "Reference" "C206"
			(at -9.014883 21.398134 270)
			(layer "B.SilkS")
			(effects
				(font
					(size 0.7 0.7)
					(thickness 0.15)
				)
				(justify mirror)
			)
		)
		(property "Value" "C_1u_25V_0402"
			(at -1.022927 -2.155213 270)
			(layer "B.Fab")
			(effects
				(font
					(size 0.7 0.7)
					(thickness 0.15)
				)
				(justify left bottom mirror)
			)
		)
		(property "Datasheet" "https://www.murata.com/products/productdetail?partno=GRM155R61E105KE11%23"
			(at 0 0 270)
			(layer "B.Fab")
			(hide yes)
			(effects
				(font
					(size 1.27 1.27)
					(thickness 0.15)
				)
				(justify mirror)
			)
		)
		(property "Description" "SMD Multilayer Ceramic Capacitor, 1 µF, 25 V, 0402 [1005 Metric], ± 10%, X5R, GRM Series"
			(at 0 0 270)
			(layer "B.Fab")
			(hide yes)
			(effects
				(font
					(size 1.27 1.27)
					(thickness 0.15)
				)
				(justify mirror)
			)
		)
		(property "MPN" "GRM155R61E105KE11J"
			(at 0 0 90)
			(unlocked yes)
			(layer "B.Fab")
			(hide yes)
			(effects
				(font
					(size 1 1)
					(thickness 0.15)
				)
				(justify mirror)
			)
		)
		(property "Manufacturer" "Murata"
			(at 0 0 90)
			(unlocked yes)
			(layer "B.Fab")
			(hide yes)
			(effects
				(font
					(size 1 1)
					(thickness 0.15)
				)
				(justify mirror)
			)
		)
		(property "License" "Apache-2.0"
			(at 0 0 90)
			(unlocked yes)
			(layer "B.Fab")
			(hide yes)
			(effects
				(font
					(size 1 1)
					(thickness 0.15)
				)
				(justify mirror)
			)
		)
		(property "Author" "Antmicro"
			(at 0 0 90)
			(unlocked yes)
			(layer "B.Fab")
			(hide yes)
			(effects
				(font
					(size 1 1)
					(thickness 0.15)
				)
				(justify mirror)
			)
		)
		(property "Val" "1u"
			(at 0 0 90)
			(unlocked yes)
			(layer "B.Fab")
			(hide yes)
			(effects
				(font
					(size 1 1)
					(thickness 0.15)
				)
				(justify mirror)
			)
		)
		(property "Voltage" "25V"
			(at 0 0 90)
			(unlocked yes)
			(layer "B.Fab")
			(hide yes)
			(effects
				(font
					(size 1 1)
					(thickness 0.15)
				)
				(justify mirror)
			)
		)
		(property "Dielectric" "X5R"
			(at 0 0 90)
			(unlocked yes)
			(layer "B.Fab")
			(hide yes)
			(effects
				(font
					(size 1 1)
					(thickness 0.15)
				)
				(justify mirror)
			)
		)
		(sheetname "/X710-AT2 power/")
		(sheetfile "x710-at2-power.kicad_sch")
		(attr smd)
		(fp_rect
			(start -0.925 0.47)
			(end 0.925 -0.47)
			(stroke
				(width 0.05)
				(type default)
			)
			(fill no)
			(layer "B.CrtYd")
		)
		(fp_line
			(start 0.504 -0.248)
			(end -0.494 -0.248)
			(stroke
				(width 0.15)
				(type solid)
			)
			(layer "B.Fab")
		)
		(fp_line
			(start -0.494 -0.248)
			(end -0.494 0.25)
			(stroke
				(width 0.15)
				(type solid)
			)
			(layer "B.Fab")
		)
		(fp_line
			(start 0.504 0.25)
			(end 0.504 -0.248)
			(stroke
				(width 0.15)
				(type solid)
			)
			(layer "B.Fab")
		)
		(fp_line
			(start -0.494 0.25)
			(end 0.504 0.25)
			(stroke
				(width 0.15)
				(type solid)
			)
			(layer "B.Fab")
		)
		(fp_text user "${REFERENCE}"
			(at -0.939 -4.599 270)
			(layer "B.Fab")
			(effects
				(font
					(size 0.7 0.7)
					(thickness 0.15)
				)
				(justify left bottom mirror)
			)
		)
		(fp_text user "License: Apache-2.0"
			(at -0.939 -5.799 270)
			(layer "B.Fab")
			(effects
				(font
					(size 0.7 0.7)
					(thickness 0.15)
				)
				(justify left bottom mirror)
			)
		)
		(fp_text user "Author: Antmicro"
			(at -0.939 -3.399 270)
			(layer "B.Fab")
			(effects
				(font
					(size 0.7 0.7)
					(thickness 0.15)
				)
				(justify left bottom mirror)
			)
		)
		(pad "1" smd roundrect
			(at -0.48 0 90)
			(size 0.59 0.64)
			(layers "B.Cu" "B.Mask" "B.Paste")
			(roundrect_rratio 0.25)
			(net 23 "GND")
			(pintype "passive")
		)
		(pad "2" smd roundrect
			(at 0.48 0 90)
			(size 0.59 0.64)
			(layers "B.Cu" "B.Mask" "B.Paste")
			(roundrect_rratio 0.25)
			(net 14 "P1_AVDDL")
			(pintype "passive")
		)
	)
	(footprint "antmicro-footprints:C_0402_1005Metric"
		(layer "B.Cu")
		(at 131.424998 123.95 -90)
		(descr "Capacitor SMD 0402")
		(tags "capacitor SMD 0402")
		(property "Reference" "C59"
			(at -7.700002 -21.900002 90)
			(layer "B.SilkS")
			(effects
				(font
					(size 0.7 0.7)
					(thickness 0.15)
				)
				(justify mirror)
			)
		)
		(property "Value" "C_1u_0402"
			(at -1.022927 -2.155213 90)
			(layer "B.Fab")
			(effects
				(font
					(size 0.7 0.7)
					(thickness 0.15)
				)
				(justify left bottom mirror)
			)
		)
		(property "Datasheet" "https://product.tdk.com/en/search/capacitor/ceramic/mlcc/info?part_no=C1005X6S1A105K050BC"
			(at 0 0 90)
			(layer "B.Fab")
			(hide yes)
			(effects
				(font
					(size 1.27 1.27)
					(thickness 0.15)
				)
				(justify mirror)
			)
		)
		(property "Description" "SMD Multilayer Ceramic Capacitor, 1 µF, 10 V, 0402 [1005 Metric], ± 10%, X6S, C"
			(at 0 0 90)
			(layer "B.Fab")
			(hide yes)
			(effects
				(font
					(size 1.27 1.27)
					(thickness 0.15)
				)
				(justify mirror)
			)
		)
		(property "MPN" "C1005X6S1A105K050BC"
			(at 0 0 270)
			(unlocked yes)
			(layer "B.Fab")
			(hide yes)
			(effects
				(font
					(size 1 1)
					(thickness 0.15)
				)
				(justify mirror)
			)
		)
		(property "Manufacturer" "TDK"
			(at 0 0 270)
			(unlocked yes)
			(layer "B.Fab")
			(hide yes)
			(effects
				(font
					(size 1 1)
					(thickness 0.15)
				)
				(justify mirror)
			)
		)
		(property "License" "Apache-2.0"
			(at 0 0 270)
			(unlocked yes)
			(layer "B.Fab")
			(hide yes)
			(effects
				(font
					(size 1 1)
					(thickness 0.15)
				)
				(justify mirror)
			)
		)
		(property "Val" "1u"
			(at 0 0 270)
			(unlocked yes)
			(layer "B.Fab")
			(hide yes)
			(effects
				(font
					(size 1 1)
					(thickness 0.15)
				)
				(justify mirror)
			)
		)
		(property "Voltage" ""
			(at 0 0 270)
			(unlocked yes)
			(layer "B.Fab")
			(hide yes)
			(effects
				(font
					(size 1 1)
					(thickness 0.15)
				)
				(justify mirror)
			)
		)
		(property "Dielectric" ""
			(at 0 0 270)
			(unlocked yes)
			(layer "B.Fab")
			(hide yes)
			(effects
				(font
					(size 1 1)
					(thickness 0.15)
				)
				(justify mirror)
			)
		)
		(property "Author" "Antmicro"
			(at 0 0 270)
			(unlocked yes)
			(layer "B.Fab")
			(hide yes)
			(effects
				(font
					(size 1 1)
					(thickness 0.15)
				)
				(justify mirror)
			)
		)
		(sheetname "/TB Controller - Power/")
		(sheetfile "tb-power.kicad_sch")
		(attr smd)
		(fp_rect
			(start -0.925 0.47)
			(end 0.925 -0.47)
			(stroke
				(width 0.05)
				(type default)
			)
			(fill no)
			(layer "B.CrtYd")
		)
		(fp_line
			(start -0.494 0.25)
			(end 0.504 0.25)
			(stroke
				(width 0.15)
				(type solid)
			)
			(layer "B.Fab")
		)
		(fp_line
			(start 0.504 0.25)
			(end 0.504 -0.248)
			(stroke
				(width 0.15)
				(type solid)
			)
			(layer "B.Fab")
		)
		(fp_line
			(start -0.494 -0.248)
			(end -0.494 0.25)
			(stroke
				(width 0.15)
				(type solid)
			)
			(layer "B.Fab")
		)
		(fp_line
			(start 0.504 -0.248)
			(end -0.494 -0.248)
			(stroke
				(width 0.15)
				(type solid)
			)
			(layer "B.Fab")
		)
		(fp_text user "Author: Antmicro"
			(at -0.939 -3.399 90)
			(layer "B.Fab")
			(effects
				(font
					(size 0.7 0.7)
					(thickness 0.15)
				)
				(justify left bottom mirror)
			)
		)
		(fp_text user "${REFERENCE}"
			(at -0.939 -4.599 90)
			(layer "B.Fab")
			(effects
				(font
					(size 0.7 0.7)
					(thickness 0.15)
				)
				(justify left bottom mirror)
			)
		)
		(fp_text user "License: Apache-2.0"
			(at -0.939 -5.799 90)
			(layer "B.Fab")
			(effects
				(font
					(size 0.7 0.7)
					(thickness 0.15)
				)
				(justify left bottom mirror)
			)
		)
		(pad "1" smd roundrect
			(at -0.48 0 270)
			(size 0.59 0.64)
			(layers "B.Cu" "B.Mask" "B.Paste")
			(roundrect_rratio 0.25)
			(net 23 "GND")
			(pintype "passive")
		)
		(pad "2" smd roundrect
			(at 0.48 0 270)
			(size 0.59 0.64)
			(layers "B.Cu" "B.Mask" "B.Paste")
			(roundrect_rratio 0.25)
			(net 402 "Net-(C52-Pad2)")
			(pintype "passive")
		)
	)
	(footprint "antmicro-footprints:C_0402_1005Metric"
		(layer "B.Cu")
		(at 129.474999 122.000001 -90)
		(descr "Capacitor SMD 0402")
		(tags "capacitor SMD 0402")
		(property "Reference" "C61"
			(at -7.700002 -21.900002 90)
			(layer "B.SilkS")
			(effects
				(font
					(size 0.7 0.7)
					(thickness 0.15)
				)
				(justify mirror)
			)
		)
		(property "Value" "C_1u_0402"
			(at -1.022927 -2.155213 90)
			(layer "B.Fab")
			(effects
				(font
					(size 0.7 0.7)
					(thickness 0.15)
				)
				(justify left bottom mirror)
			)
		)
		(property "Datasheet" "https://product.tdk.com/en/search/capacitor/ceramic/mlcc/info?part_no=C1005X6S1A105K050BC"
			(at 0 0 90)
			(layer "B.Fab")
			(hide yes)
			(effects
				(font
					(size 1.27 1.27)
					(thickness 0.15)
				)
				(justify mirror)
			)
		)
		(property "Description" "SMD Multilayer Ceramic Capacitor, 1 µF, 10 V, 0402 [1005 Metric], ± 10%, X6S, C"
			(at 0 0 90)
			(layer "B.Fab")
			(hide yes)
			(effects
				(font
					(size 1.27 1.27)
					(thickness 0.15)
				)
				(justify mirror)
			)
		)
		(property "MPN" "C1005X6S1A105K050BC"
			(at 0 0 270)
			(unlocked yes)
			(layer "B.Fab")
			(hide yes)
			(effects
				(font
					(size 1 1)
					(thickness 0.15)
				)
				(justify mirror)
			)
		)
		(property "Manufacturer" "TDK"
			(at 0 0 270)
			(unlocked yes)
			(layer "B.Fab")
			(hide yes)
			(effects
				(font
					(size 1 1)
					(thickness 0.15)
				)
				(justify mirror)
			)
		)
		(property "License" "Apache-2.0"
			(at 0 0 270)
			(unlocked yes)
			(layer "B.Fab")
			(hide yes)
			(effects
				(font
					(size 1 1)
					(thickness 0.15)
				)
				(justify mirror)
			)
		)
		(property "Val" "1u"
			(at 0 0 270)
			(unlocked yes)
			(layer "B.Fab")
			(hide yes)
			(effects
				(font
					(size 1 1)
					(thickness 0.15)
				)
				(justify mirror)
			)
		)
		(property "Voltage" ""
			(at 0 0 270)
			(unlocked yes)
			(layer "B.Fab")
			(hide yes)
			(effects
				(font
					(size 1 1)
					(thickness 0.15)
				)
				(justify mirror)
			)
		)
		(property "Dielectric" ""
			(at 0 0 270)
			(unlocked yes)
			(layer "B.Fab")
			(hide yes)
			(effects
				(font
					(size 1 1)
					(thickness 0.15)
				)
				(justify mirror)
			)
		)
		(property "Author" "Antmicro"
			(at 0 0 270)
			(unlocked yes)
			(layer "B.Fab")
			(hide yes)
			(effects
				(font
					(size 1 1)
					(thickness 0.15)
				)
				(justify mirror)
			)
		)
		(sheetname "/TB Controller - Power/")
		(sheetfile "tb-power.kicad_sch")
		(attr smd)
		(fp_rect
			(start -0.925 0.47)
			(end 0.925 -0.47)
			(stroke
				(width 0.05)
				(type default)
			)
			(fill no)
			(layer "B.CrtYd")
		)
		(fp_line
			(start -0.494 0.25)
			(end 0.504 0.25)
			(stroke
				(width 0.15)
				(type solid)
			)
			(layer "B.Fab")
		)
		(fp_line
			(start 0.504 0.25)
			(end 0.504 -0.248)
			(stroke
				(width 0.15)
				(type solid)
			)
			(layer "B.Fab")
		)
		(fp_line
			(start -0.494 -0.248)
			(end -0.494 0.25)
			(stroke
				(width 0.15)
				(type solid)
			)
			(layer "B.Fab")
		)
		(fp_line
			(start 0.504 -0.248)
			(end -0.494 -0.248)
			(stroke
				(width 0.15)
				(type solid)
			)
			(layer "B.Fab")
		)
		(fp_text user "${REFERENCE}"
			(at -0.939 -4.599 90)
			(layer "B.Fab")
			(effects
				(font
					(size 0.7 0.7)
					(thickness 0.15)
				)
				(justify left bottom mirror)
			)
		)
		(fp_text user "License: Apache-2.0"
			(at -0.939 -5.799 90)
			(layer "B.Fab")
			(effects
				(font
					(size 0.7 0.7)
					(thickness 0.15)
				)
				(justify left bottom mirror)
			)
		)
		(fp_text user "Author: Antmicro"
			(at -0.939 -3.399 90)
			(layer "B.Fab")
			(effects
				(font
					(size 0.7 0.7)
					(thickness 0.15)
				)
				(justify left bottom mirror)
			)
		)
		(pad "1" smd roundrect
			(at -0.48 0 270)
			(size 0.59 0.64)
			(layers "B.Cu" "B.Mask" "B.Paste")
			(roundrect_rratio 0.25)
			(net 23 "GND")
			(pintype "passive")
		)
		(pad "2" smd roundrect
			(at 0.48 0 270)
			(size 0.59 0.64)
			(layers "B.Cu" "B.Mask" "B.Paste")
			(roundrect_rratio 0.25)
			(net 404 "Net-(C58-Pad2)")
			(pintype "passive")
		)
	)
	(footprint "antmicro-footprints:C_0402_1005Metric"
		(layer "B.Cu")
		(at 147.481865 75.285116)
		(descr "Capacitor SMD 0402")
		(tags "capacitor SMD 0402")
		(property "Reference" "C234"
			(at 18.618135 9.464883 180)
			(layer "B.SilkS")
			(effects
				(font
					(size 0.7 0.7)
					(thickness 0.15)
				)
				(justify mirror)
			)
		)
		(property "Value" "C_1u_25V_0402"
			(at -1.022927 -2.155213 180)
			(layer "B.Fab")
			(effects
				(font
					(size 0.7 0.7)
					(thickness 0.15)
				)
				(justify left bottom mirror)
			)
		)
		(property "Datasheet" "https://www.murata.com/products/productdetail?partno=GRM155R61E105KE11%23"
			(at 0 0 180)
			(layer "B.Fab")
			(hide yes)
			(effects
				(font
					(size 1.27 1.27)
					(thickness 0.15)
				)
				(justify mirror)
			)
		)
		(property "Description" "SMD Multilayer Ceramic Capacitor, 1 µF, 25 V, 0402 [1005 Metric], ± 10%, X5R, GRM Series"
			(at 0 0 180)
			(layer "B.Fab")
			(hide yes)
			(effects
				(font
					(size 1.27 1.27)
					(thickness 0.15)
				)
				(justify mirror)
			)
		)
		(property "MPN" "GRM155R61E105KE11J"
			(at 0 0 0)
			(unlocked yes)
			(layer "B.Fab")
			(hide yes)
			(effects
				(font
					(size 1 1)
					(thickness 0.15)
				)
				(justify mirror)
			)
		)
		(property "Manufacturer" "Murata"
			(at 0 0 0)
			(unlocked yes)
			(layer "B.Fab")
			(hide yes)
			(effects
				(font
					(size 1 1)
					(thickness 0.15)
				)
				(justify mirror)
			)
		)
		(property "License" "Apache-2.0"
			(at 0 0 0)
			(unlocked yes)
			(layer "B.Fab")
			(hide yes)
			(effects
				(font
					(size 1 1)
					(thickness 0.15)
				)
				(justify mirror)
			)
		)
		(property "Author" "Antmicro"
			(at 0 0 0)
			(unlocked yes)
			(layer "B.Fab")
			(hide yes)
			(effects
				(font
					(size 1 1)
					(thickness 0.15)
				)
				(justify mirror)
			)
		)
		(property "Val" "1u"
			(at 0 0 0)
			(unlocked yes)
			(layer "B.Fab")
			(hide yes)
			(effects
				(font
					(size 1 1)
					(thickness 0.15)
				)
				(justify mirror)
			)
		)
		(property "Voltage" "25V"
			(at 0 0 0)
			(unlocked yes)
			(layer "B.Fab")
			(hide yes)
			(effects
				(font
					(size 1 1)
					(thickness 0.15)
				)
				(justify mirror)
			)
		)
		(property "Dielectric" "X5R"
			(at 0 0 0)
			(unlocked yes)
			(layer "B.Fab")
			(hide yes)
			(effects
				(font
					(size 1 1)
					(thickness 0.15)
				)
				(justify mirror)
			)
		)
		(sheetname "/X710-AT2 power/")
		(sheetfile "x710-at2-power.kicad_sch")
		(attr smd)
		(fp_rect
			(start -0.925 0.47)
			(end 0.925 -0.47)
			(stroke
				(width 0.05)
				(type default)
			)
			(fill no)
			(layer "B.CrtYd")
		)
		(fp_line
			(start -0.494 -0.248)
			(end -0.494 0.25)
			(stroke
				(width 0.15)
				(type solid)
			)
			(layer "B.Fab")
		)
		(fp_line
			(start -0.494 0.25)
			(end 0.504 0.25)
			(stroke
				(width 0.15)
				(type solid)
			)
			(layer "B.Fab")
		)
		(fp_line
			(start 0.504 -0.248)
			(end -0.494 -0.248)
			(stroke
				(width 0.15)
				(type solid)
			)
			(layer "B.Fab")
		)
		(fp_line
			(start 0.504 0.25)
			(end 0.504 -0.248)
			(stroke
				(width 0.15)
				(type solid)
			)
			(layer "B.Fab")
		)
		(fp_text user "Author: Antmicro"
			(at -0.939 -3.399 180)
			(layer "B.Fab")
			(effects
				(font
					(size 0.7 0.7)
					(thickness 0.15)
				)
				(justify left bottom mirror)
			)
		)
		(fp_text user "License: Apache-2.0"
			(at -0.939 -5.799 180)
			(layer "B.Fab")
			(effects
				(font
					(size 0.7 0.7)
					(thickness 0.15)
				)
				(justify left bottom mirror)
			)
		)
		(fp_text user "${REFERENCE}"
			(at -0.939 -4.599 180)
			(layer "B.Fab")
			(effects
				(font
					(size 0.7 0.7)
					(thickness 0.15)
				)
				(justify left bottom mirror)
			)
		)
		(pad "1" smd roundrect
			(at -0.48 0)
			(size 0.59 0.64)
			(layers "B.Cu" "B.Mask" "B.Paste")
			(roundrect_rratio 0.25)
			(net 23 "GND")
			(pintype "passive")
		)
		(pad "2" smd roundrect
			(at 0.48 0)
			(size 0.59 0.64)
			(layers "B.Cu" "B.Mask" "B.Paste")
			(roundrect_rratio 0.25)
			(net 9 "VCCD")
			(pintype "passive")
		)
	)
)
